#ISCELL
  mstr_misc dns *
  *
#ISCELL
  pure_quanta quanta_title_block_c *
  *
#ISCELL
  standard offpage *
  page210_i15
#CELL
  pure_quanta q_res *
  page210_i19
#CELL
  pure_quanta q_res *
  page210_i20
#ISCELL
  standard offpage *
  page210_i21
#CELL
  pure_quanta q_res *
  page210_i25
#ISCELL
  standard offpage *
  page210_i26
#ISCELL
  standard offpage *
  page210_i29
#CELL
  pure_quanta q_res *
  page210_i54
#ISCELL
  standard offpage *
  page210_i55
#ISCELL
  standard offpage *
  page210_i58
#CELL
  pure_quanta q_res *
  page210_i59
#CELL
  pure_quanta q_res *
  page210_i60
#CELL
  pure_quanta q_res *
  page210_i61
#ISCELL
  logical_power universal_power *
  page210_i62
#CELL
  pure_quanta q_res *
  page210_i63
#ISCELL
  logical_power universal_gnd *
  page210_i64
#ISCELL
  standard offpage *
  page210_i65
#ISCELL
  standard offpage *
  page210_i67
#ISCELL
  standard offpage *
  page210_i72
#CELL
  pure_quanta q_res *
  page210_i75
#CELL
  pure_quanta q_res *
  page210_i76
#ISCELL
  logical_power universal_power *
  page210_i77
#ISCELL
  logical_power universal_gnd *
  page210_i78
#CELL
  pure_quanta conn8_210hp1080br1 *
  page210_i79
#ISCELL
  standard offpage *
  page210_i81
#ISCELL
  standard offpage *
  page210_i82
#ISCELL
  standard offpage *
  page210_i83
#ISCELL
  standard offpage *
  page210_i84
#CELL
  pure_quanta q_cap *
  page210_i86
#CELL
  pure_quanta q_cap *
  page210_i88
#ISCELL
  logical_power universal_gnd *
  page210_i89
#ISCELL
  logical_power universal_gnd *
  page210_i90
#CELL
  pure_quanta schottky_12 *
  page210_i91
#ISCELL
  logical_power universal_power *
  page210_i92
